(kicad_pcb
	(version 20241229)
	(generator "pcbnew")
	(generator_version "9.0")
	(general
		(thickness 1.552)
		(legacy_teardrops no)
	)
	(paper "A4")
	(title_block
		(date "2023-07-25")
		(rev "1.1.4")
		(comment 9 "footprints 201-205 of 379")
	)
	(layers
		(0 "F.Cu" signal)
		(4 "In1.Cu" signal)
		(6 "In2.Cu" signal)
		(8 "In3.Cu" signal)
		(10 "In4.Cu" signal)
		(12 "In5.Cu" signal)
		(14 "In6.Cu" signal)
		(2 "B.Cu" signal)
		(9 "F.Adhes" user "F.Adhesive")
		(11 "B.Adhes" user "B.Adhesive")
		(13 "F.Paste" user)
		(15 "B.Paste" user)
		(5 "F.SilkS" user "F.Silkscreen")
		(7 "B.SilkS" user "B.Silkscreen")
		(1 "F.Mask" user)
		(3 "B.Mask" user)
		(17 "Dwgs.User" user "User.Drawings")
		(19 "Cmts.User" user "User.Comments")
		(21 "Eco1.User" user "User.Eco1")
		(23 "Eco2.User" user "User.Eco2")
		(25 "Edge.Cuts" user)
		(27 "Margin" user)
		(31 "F.CrtYd" user "F.Courtyard")
		(29 "B.CrtYd" user "B.Courtyard")
		(35 "F.Fab" user)
		(33 "B.Fab" user)
	)
	(footprint "antmicro-footprints:C_0603_1608Metric"
		(layer "F.Cu")
		(at 145.74 109.9 -90)
		(descr "Capacitor SMD 0603")
		(tags "capacitor 0603")
		(property "Reference" "C19"
			(at -1.16 -1.69 90)
			(layer "F.SilkS")
			(effects
				(font
					(size 0.65 0.65)
					(thickness 0.15)
				)
				(justify right bottom)
			)
		)
		(property "Value" "C_1u_0603"
			(at 0 1.6 90)
			(layer "F.Fab")
			(hide yes)
			(effects
				(font
					(size 0.7 0.7)
					(thickness 0.15)
				)
				(justify right bottom)
			)
		)
		(property "Datasheet" "https://spicat.kyocera-avx.com/product/mlcc/chartview/0603YD105KAT2A/"
			(at 0 0 270)
			(layer "F.Fab")
			(hide yes)
			(effects
				(font
					(size 1.27 1.27)
					(thickness 0.15)
				)
			)
		)
		(property "Description" "SMD Multilayer Ceramic Capacitor, 1 µF, 16 V, 0603 [1608 Metric], ± 10%, X5R, AVX 0603 MLCC"
			(at 0 0 270)
			(layer "F.Fab")
			(hide yes)
			(effects
				(font
					(size 1.27 1.27)
					(thickness 0.15)
				)
			)
		)
		(property "Author" "Antmicro"
			(at 35.84 255.64 0)
			(layer "F.Fab")
			(hide yes)
			(effects
				(font
					(size 1 1)
					(thickness 0.15)
				)
			)
		)
		(property "Dielectric" ""
			(at 35.84 255.64 0)
			(layer "F.Fab")
			(hide yes)
			(effects
				(font
					(size 1 1)
					(thickness 0.15)
				)
			)
		)
		(property "License" "Apache-2.0"
			(at 35.84 255.64 0)
			(layer "F.Fab")
			(hide yes)
			(effects
				(font
					(size 1 1)
					(thickness 0.15)
				)
			)
		)
		(property "MPN" "0603YD105KAT2A"
			(at 35.84 255.64 0)
			(layer "F.Fab")
			(hide yes)
			(effects
				(font
					(size 1 1)
					(thickness 0.15)
				)
			)
		)
		(property "Manufacturer" "KYOCERA AVX"
			(at 35.84 255.64 0)
			(layer "F.Fab")
			(hide yes)
			(effects
				(font
					(size 1 1)
					(thickness 0.15)
				)
			)
		)
		(property "Val" "1u"
			(at 35.84 255.64 0)
			(layer "F.Fab")
			(hide yes)
			(effects
				(font
					(size 1 1)
					(thickness 0.15)
				)
			)
		)
		(property "Voltage" ""
			(at 35.84 255.64 0)
			(layer "F.Fab")
			(hide yes)
			(effects
				(font
					(size 1 1)
					(thickness 0.15)
				)
			)
		)
		(sheetname "/Power Supply/")
		(sheetfile "supply.kicad_sch")
		(attr smd)
		(fp_line
			(start -0.15 0.4)
			(end 0.15 0.4)
			(stroke
				(width 0.15)
				(type solid)
			)
			(layer "F.SilkS")
		)
		(fp_line
			(start -0.15 -0.4)
			(end 0.15 -0.4)
			(stroke
				(width 0.15)
				(type solid)
			)
			(layer "F.SilkS")
		)
		(fp_rect
			(start -1.25 -0.65)
			(end 1.25 0.65)
			(stroke
				(width 0.05)
				(type solid)
			)
			(fill no)
			(layer "F.CrtYd")
		)
		(fp_rect
			(start -0.8 -0.4)
			(end 0.8 0.4)
			(stroke
				(width 0.15)
				(type solid)
			)
			(fill no)
			(layer "F.Fab")
		)
		(fp_text user "${REFERENCE}"
			(at -1.682 3.895 270)
			(layer "F.Fab")
			(effects
				(font
					(size 0.7 0.7)
					(thickness 0.15)
				)
				(justify left bottom)
			)
		)
		(fp_text user "License: Apache-2.0"
			(at -1.682 5.895 270)
			(layer "F.Fab")
			(effects
				(font
					(size 0.7 0.7)
					(thickness 0.15)
				)
				(justify left bottom)
			)
		)
		(fp_text user "Author: Antmicro"
			(at -1.682 4.894 270)
			(layer "F.Fab")
			(effects
				(font
					(size 0.7 0.7)
					(thickness 0.15)
				)
				(justify left bottom)
			)
		)
		(pad "1" smd roundrect
			(at -0.7 0 270)
			(size 0.8 1)
			(layers "F.Cu" "F.Mask" "F.Paste")
			(roundrect_rratio 0.2)
			(net 1 "GND")
			(pintype "passive")
		)
		(pad "2" smd roundrect
			(at 0.7 0 270)
			(size 0.8 1)
			(layers "F.Cu" "F.Mask" "F.Paste")
			(roundrect_rratio 0.2)
			(net 2 "+3V3")
			(pintype "passive")
		)
	)
	(footprint "antmicro-footprints:LED_0603_1608Metric_G"
		(layer "F.Cu")
		(at 164.79 70.3 90)
		(descr "LED SMD 0603 Green")
		(tags "LED SMD 0603 Green")
		(property "Reference" "D1"
			(at 1.2 -0.34 90)
			(layer "F.SilkS")
			(effects
				(font
					(size 0.65 0.65)
					(thickness 0.15)
				)
				(justify left top)
			)
		)
		(property "Value" "LED_G_0603_LTST-C190GKT"
			(at 0 1.6 90)
			(layer "F.Fab")
			(hide yes)
			(effects
				(font
					(size 0.7 0.7)
					(thickness 0.15)
				)
				(justify left top)
			)
		)
		(property "Datasheet" "https://media.digikey.com/pdf/Data%20Sheets/Lite-On%20PDFs/LTST-C190GKT.pdf"
			(at 0 0 90)
			(layer "F.Fab")
			(hide yes)
			(effects
				(font
					(size 1.27 1.27)
					(thickness 0.15)
				)
			)
		)
		(property "Description" "LED, Green, SMD, 0603, 20 mA, 2.1 V, 569 nm"
			(at 0 0 90)
			(layer "F.Fab")
			(hide yes)
			(effects
				(font
					(size 1.27 1.27)
					(thickness 0.15)
				)
			)
		)
		(property "Author" "Antmicro"
			(at 94.49 235.09 0)
			(layer "F.Fab")
			(hide yes)
			(effects
				(font
					(size 1 1)
					(thickness 0.15)
				)
			)
		)
		(property "License" "Apache-2.0"
			(at 94.49 235.09 0)
			(layer "F.Fab")
			(hide yes)
			(effects
				(font
					(size 1 1)
					(thickness 0.15)
				)
			)
		)
		(property "MPN" "LTST-C190GKT"
			(at 94.49 235.09 0)
			(layer "F.Fab")
			(hide yes)
			(effects
				(font
					(size 1 1)
					(thickness 0.15)
				)
			)
		)
		(property "Manufacturer" "Lite-On"
			(at 94.49 235.09 0)
			(layer "F.Fab")
			(hide yes)
			(effects
				(font
					(size 1 1)
					(thickness 0.15)
				)
			)
		)
		(property "Color" "Green"
			(at 0 0 90)
			(unlocked yes)
			(layer "F.Fab")
			(hide yes)
			(effects
				(font
					(size 1 1)
					(thickness 0.15)
				)
			)
		)
		(sheetname "/Power Supply/")
		(sheetfile "supply.kicad_sch")
		(attr smd)
		(fp_line
			(start 0.22 -0.35)
			(end -0.22 -0.35)
			(stroke
				(width 0.15)
				(type solid)
			)
			(layer "F.SilkS")
		)
		(fp_line
			(start -1.18 -0.319)
			(end -1.18 0.321)
			(stroke
				(width 0.15)
				(type solid)
			)
			(layer "F.SilkS")
		)
		(fp_line
			(start 0.105328 0.001008)
			(end 0.24 0.001)
			(stroke
				(width 0.1)
				(type solid)
			)
			(layer "F.SilkS")
		)
		(fp_line
			(start -0.094672 0.001008)
			(end 0.105328 -0.198992)
			(stroke
				(width 0.1)
				(type solid)
			)
			(layer "F.SilkS")
		)
		(fp_line
			(start -0.094672 0.001008)
			(end -0.24 0.001008)
			(stroke
				(width 0.1)
				(type solid)
			)
			(layer "F.SilkS")
		)
		(fp_line
			(start 0.105328 0.201008)
			(end 0.105328 -0.198992)
			(stroke
				(width 0.1)
				(type solid)
			)
			(layer "F.SilkS")
		)
		(fp_line
			(start 0.105328 0.201008)
			(end -0.094672 0.001008)
			(stroke
				(width 0.1)
				(type solid)
			)
			(layer "F.SilkS")
		)
		(fp_line
			(start -0.094672 0.201008)
			(end -0.094672 -0.198992)
			(stroke
				(width 0.1)
				(type solid)
			)
			(layer "F.SilkS")
		)
		(fp_line
			(start 0.22 0.35)
			(end -0.22 0.35)
			(stroke
				(width 0.15)
				(type solid)
			)
			(layer "F.SilkS")
		)
		(fp_rect
			(start 1.25 0.65)
			(end -1.25 -0.65)
			(stroke
				(width 0.05)
				(type solid)
			)
			(fill no)
			(layer "F.CrtYd")
		)
		(fp_line
			(start 0.201 -0.202)
			(end -0.101 0)
			(stroke
				(width 0.15)
				(type solid)
			)
			(layer "F.Fab")
		)
		(fp_line
			(start -0.199 -0.202)
			(end -0.199 0.1)
			(stroke
				(width 0.15)
				(type solid)
			)
			(layer "F.Fab")
		)
		(fp_line
			(start 0.599 0)
			(end 0.201 0)
			(stroke
				(width 0.15)
				(type solid)
			)
			(layer "F.Fab")
		)
		(fp_line
			(start 0.201 0)
			(end 0.201 -0.202)
			(stroke
				(width 0.15)
				(type solid)
			)
			(layer "F.Fab")
		)
		(fp_line
			(start -0.101 0)
			(end 0.201 0.2)
			(stroke
				(width 0.15)
				(type solid)
			)
			(layer "F.Fab")
		)
		(fp_line
			(start -0.199 0)
			(end -0.597 0)
			(stroke
				(width 0.15)
				(type solid)
			)
			(layer "F.Fab")
		)
		(fp_line
			(start 0.201 0.2)
			(end 0.201 0)
			(stroke
				(width 0.15)
				(type solid)
			)
			(layer "F.Fab")
		)
		(fp_line
			(start -0.199 0.2)
			(end -0.199 0.1)
			(stroke
				(width 0.15)
				(type solid)
			)
			(layer "F.Fab")
		)
		(fp_rect
			(start 0.848 0.4)
			(end -0.85 -0.402)
			(stroke
				(width 0.15)
				(type solid)
			)
			(fill no)
			(layer "F.Fab")
		)
		(fp_text user "Author: Antmicro"
			(at -1.4224 4.799 90)
			(layer "F.Fab")
			(effects
				(font
					(size 0.7 0.7)
					(thickness 0.15)
				)
				(justify left bottom)
			)
		)
		(fp_text user "License: Apache-2.0"
			(at -1.4224 3.599 90)
			(layer "F.Fab")
			(effects
				(font
					(size 0.7 0.7)
					(thickness 0.15)
				)
				(justify left bottom)
			)
		)
		(fp_text user "${REFERENCE}"
			(at -1.4224 5.999 90)
			(layer "F.Fab")
			(effects
				(font
					(size 0.7 0.7)
					(thickness 0.15)
				)
				(justify left bottom)
			)
		)
		(pad "1" smd roundrect
			(at -0.7 0 270)
			(size 0.8 1)
			(layers "F.Cu" "F.Mask" "F.Paste")
			(roundrect_rratio 0.2)
			(net 1 "GND")
			(pinfunction "C")
			(pintype "passive")
		)
		(pad "2" smd roundrect
			(at 0.7 0 270)
			(size 0.8 1)
			(layers "F.Cu" "F.Mask" "F.Paste")
			(roundrect_rratio 0.2)
			(net 58 "Net-(D1-A)")
			(pinfunction "A")
			(pintype "passive")
		)
	)
	(footprint "antmicro-footprints:R_0402_1005Metric"
		(layer "F.Cu")
		(at 165.19 59.04 180)
		(descr "Resistor SMD 0402")
		(tags "resistor SMD 0402")
		(property "Reference" "R27"
			(at 1.06 0.7 180)
			(layer "F.SilkS")
			(effects
				(font
					(size 0.65 0.65)
					(thickness 0.15)
				)
				(justify left bottom)
			)
		)
		(property "Value" "R_10k_0402"
			(at 0 1.4 180)
			(layer "F.Fab")
			(hide yes)
			(effects
				(font
					(size 0.7 0.7)
					(thickness 0.15)
				)
				(justify left bottom)
			)
		)
		(property "Datasheet" "https://www.bourns.com/docs/product-datasheets/cr.pdf"
			(at 0 0 180)
			(layer "F.Fab")
			(hide yes)
			(effects
				(font
					(size 1.27 1.27)
					(thickness 0.15)
				)
			)
		)
		(property "Description" "SMD Chip Resistor, 10 kohm, ± 1%, 62.5 mW, 0402 [1005 Metric], Thick Film, General Purpose"
			(at 0 0 180)
			(layer "F.Fab")
			(hide yes)
			(effects
				(font
					(size 1.27 1.27)
					(thickness 0.15)
				)
			)
		)
		(property "Author" "Antmicro"
			(at 330.38 118.08 0)
			(layer "F.Fab")
			(hide yes)
			(effects
				(font
					(size 1 1)
					(thickness 0.15)
				)
			)
		)
		(property "License" "Apache-2.0"
			(at 330.38 118.08 0)
			(layer "F.Fab")
			(hide yes)
			(effects
				(font
					(size 1 1)
					(thickness 0.15)
				)
			)
		)
		(property "MPN" "CR0402-FX-1002GLF"
			(at 330.38 118.08 0)
			(layer "F.Fab")
			(hide yes)
			(effects
				(font
					(size 1 1)
					(thickness 0.15)
				)
			)
		)
		(property "Manufacturer" "Bourns"
			(at 330.38 118.08 0)
			(layer "F.Fab")
			(hide yes)
			(effects
				(font
					(size 1 1)
					(thickness 0.15)
				)
			)
		)
		(property "Tolerance" "1%"
			(at 330.38 118.08 0)
			(layer "F.Fab")
			(hide yes)
			(effects
				(font
					(size 1 1)
					(thickness 0.15)
				)
			)
		)
		(property "Val" "10k"
			(at 330.38 118.08 0)
			(layer "F.Fab")
			(hide yes)
			(effects
				(font
					(size 1 1)
					(thickness 0.15)
				)
			)
		)
		(sheetname "/Power Supply/")
		(sheetfile "supply.kicad_sch")
		(attr smd)
		(fp_rect
			(start -0.925 -0.47)
			(end 0.925 0.47)
			(stroke
				(width 0.05)
				(type default)
			)
			(fill no)
			(layer "F.CrtYd")
		)
		(fp_rect
			(start -0.5 -0.25)
			(end 0.5 0.25)
			(stroke
				(width 0.15)
				(type solid)
			)
			(fill no)
			(layer "F.Fab")
		)
		(fp_text user "${REFERENCE}"
			(at -0.95 3.168 180)
			(layer "F.Fab")
			(effects
				(font
					(size 0.7 0.7)
					(thickness 0.15)
				)
				(justify left bottom)
			)
		)
		(fp_text user "License: Apache-2.0"
			(at -0.95 5.169 180)
			(layer "F.Fab")
			(effects
				(font
					(size 0.7 0.7)
					(thickness 0.15)
				)
				(justify left bottom)
			)
		)
		(fp_text user "Author: Antmicro"
			(at -0.95 4.169 180)
			(layer "F.Fab")
			(effects
				(font
					(size 0.7 0.7)
					(thickness 0.15)
				)
				(justify left bottom)
			)
		)
		(pad "1" smd roundrect
			(at -0.48 0 180)
			(size 0.59 0.64)
			(layers "F.Cu" "F.Mask" "F.Paste")
			(roundrect_rratio 0.25)
			(net 1 "GND")
			(pintype "passive")
		)
		(pad "2" smd roundrect
			(at 0.48 0 180)
			(size 0.59 0.64)
			(layers "F.Cu" "F.Mask" "F.Paste")
			(roundrect_rratio 0.25)
			(net 270 "Net-(U7-FB)")
			(pintype "passive")
		)
	)
	(footprint "antmicro-footprints:TP_SMD_0.75mm"
		(layer "F.Cu")
		(at 100.25 69.5)
		(property "Reference" "TP25"
			(at 0.53 0.39 0)
			(layer "F.SilkS")
			(effects
				(font
					(size 0.65 0.65)
					(thickness 0.15)
				)
				(justify left bottom)
			)
		)
		(property "Value" "TP_0.75mm_SMD"
			(at 0 1.2 0)
			(layer "F.Fab")
			(hide yes)
			(effects
				(font
					(size 0.7 0.7)
					(thickness 0.15)
				)
				(justify left bottom)
			)
		)
		(property "Description" "SMT test point"
			(at 0 0 0)
			(layer "F.Fab")
			(hide yes)
			(effects
				(font
					(size 1.27 1.27)
					(thickness 0.15)
				)
			)
		)
		(property "Author" "Antmicro"
			(at 0 0 0)
			(layer "F.Fab")
			(hide yes)
			(effects
				(font
					(size 1 1)
					(thickness 0.15)
				)
			)
		)
		(property "License" "Apache-2.0"
			(at 0 0 0)
			(layer "F.Fab")
			(hide yes)
			(effects
				(font
					(size 1 1)
					(thickness 0.15)
				)
			)
		)
		(property "MPN" ""
			(at 0 0 0)
			(layer "F.Fab")
			(hide yes)
			(effects
				(font
					(size 1 1)
					(thickness 0.15)
				)
			)
		)
		(property "Manufacturer" ""
			(at 0 0 0)
			(layer "F.Fab")
			(hide yes)
			(effects
				(font
					(size 1 1)
					(thickness 0.15)
				)
			)
		)
		(sheetname "/SDI/")
		(sheetfile "sdi.kicad_sch")
		(attr exclude_from_pos_files)
		(fp_circle
			(center 0 0)
			(end 0.475 0)
			(stroke
				(width 0.05)
				(type default)
			)
			(fill no)
			(layer "F.CrtYd")
		)
		(fp_text user "Author: Antmicro"
			(at -0.4 3.901 0)
			(layer "F.Fab")
			(effects
				(font
					(size 0.7 0.7)
					(thickness 0.15)
				)
				(justify left bottom)
			)
		)
		(fp_text user "License: Apache-2.0"
			(at -0.4 5.101 0)
			(layer "F.Fab")
			(effects
				(font
					(size 0.7 0.7)
					(thickness 0.15)
				)
				(justify left bottom)
			)
		)
		(fp_text user "${REFERENCE}"
			(at -0.4 2.7 0)
			(layer "F.Fab")
			(effects
				(font
					(size 0.7 0.7)
					(thickness 0.15)
				)
				(justify left bottom)
			)
		)
		(pad "1" smd circle
			(at 0 0)
			(size 0.75 0.75)
			(layers "F.Cu" "F.Mask")
			(net 217 "/SDI/SDI_STAT1")
			(pinfunction "1")
			(pintype "passive")
		)
	)
	(footprint "antmicro-footprints:MP_Pad5.4mm_Drill2.7mm"
		(layer "F.Cu")
		(at 80.03 60.15)
		(descr "Mounting Hole 2.7mm, M2.5")
		(tags "mounting hole 2.7mm m2.5")
		(property "Reference" "MP1"
			(at 0 -2.9 0)
			(layer "F.SilkS")
			(hide yes)
			(effects
				(font
					(size 0.7 0.7)
					(thickness 0.15)
				)
				(justify left bottom)
			)
		)
		(property "Value" "MP_Pad5.4mm_Drill2.7mm"
			(at 0 3.6 0)
			(layer "F.Fab")
			(effects
				(font
					(size 0.7 0.7)
					(thickness 0.15)
				)
				(justify left bottom)
			)
		)
		(property "Description" "Mechanical part"
			(at 0 0 0)
			(layer "F.Fab")
			(hide yes)
			(effects
				(font
					(size 1.27 1.27)
					(thickness 0.15)
				)
			)
		)
		(property "Author" "Antmicro"
			(at 0 0 0)
			(unlocked yes)
			(layer "F.Fab")
			(hide yes)
			(effects
				(font
					(size 1 1)
					(thickness 0.15)
				)
			)
		)
		(property "License" "Apache-2.0"
			(at 0 0 0)
			(unlocked yes)
			(layer "F.Fab")
			(hide yes)
			(effects
				(font
					(size 1 1)
					(thickness 0.15)
				)
			)
		)
		(sheetname "/")
		(sheetfile "sdi-mipi-video-converter.kicad_sch")
		(attr exclude_from_pos_files exclude_from_bom)
		(fp_circle
			(center 0 0)
			(end 2.95 0)
			(stroke
				(width 0.05)
				(type default)
			)
			(fill no)
			(layer "F.CrtYd")
		)
		(fp_text user "${REFERENCE}"
			(at -8.4 6 0)
			(layer "F.Fab")
			(effects
				(font
					(size 0.7 0.7)
					(thickness 0.15)
				)
				(justify left bottom)
			)
		)
		(fp_text user "License: Apache-2.0"
			(at -8.4 8.4 0)
			(layer "F.Fab")
			(effects
				(font
					(size 0.7 0.7)
					(thickness 0.15)
				)
				(justify left bottom)
			)
		)
		(fp_text user "Author: Antmicro"
			(at -8.4 7.2 0)
			(layer "F.Fab")
			(effects
				(font
					(size 0.7 0.7)
					(thickness 0.15)
				)
				(justify left bottom)
			)
		)
		(pad "1" thru_hole circle
			(at 0 0)
			(size 5.4 5.4)
			(drill 2.7)
			(layers "*.Cu" "*.Mask")
			(remove_unused_layers no)
			(net 398 "unconnected-(MP1-Pad1)")
			(pintype "passive+no_connect")
			(solder_paste_margin_ratio -1)
		)
	)
)
